(kicad_pcb
	(version 20260206)
	(generator "pcbnew")
	(generator_version "10.0")
	(general
		(thickness 1.6)
		(legacy_teardrops no)
	)
	(paper "A4")
	(title_block
		(title "04192023_DAF0TMB3IC0_F0TG_MB_C_brd_V02_OCP.brd")
		(comment 1 "Grand Teton / footprints 3994-4002 of 8354")
	)
	(layers
		(0 "F.Cu" signal "TOP")
		(4 "In1.Cu" signal "GND")
		(6 "In2.Cu" signal "IN1")
		(8 "In3.Cu" signal "GND1")
		(10 "In4.Cu" signal "IN2")
		(12 "In5.Cu" signal "GND2")
		(14 "In6.Cu" signal "IN3")
		(16 "In7.Cu" signal "GND3")
		(18 "In8.Cu" signal "VCC")
		(20 "In9.Cu" signal "VCC1")
		(22 "In10.Cu" signal "GND4")
		(24 "In11.Cu" signal "IN4")
		(26 "In12.Cu" signal "GND5")
		(28 "In13.Cu" signal "IN5")
		(30 "In14.Cu" signal "GND6")
		(32 "In15.Cu" signal "IN6")
		(34 "In16.Cu" signal "GND7")
		(2 "B.Cu" signal "BOTTOM")
		(9 "F.Adhes" user "F.Adhesive")
		(11 "B.Adhes" user "B.Adhesive")
		(13 "F.Paste" user "Package Geometry/Pastemask Top")
		(15 "B.Paste" user "Package Geometry/Pastemask Bottom")
		(5 "F.SilkS" user "Ref Des/Silkscreen Top")
		(7 "B.SilkS" user "Ref Des/Silkscreen Bottom")
		(1 "F.Mask" user "Board Geometry/Soldermask Top")
		(3 "B.Mask" user "Board Geometry/Soldermask Bottom")
		(17 "Dwgs.User" user "User.Drawings")
		(19 "Cmts.User" user "User.Comments")
		(21 "Eco1.User" user "User.Eco1")
		(23 "Eco2.User" user "User.Eco2")
		(25 "Edge.Cuts" user "Board Geometry/Outline")
		(27 "Margin" user)
		(31 "F.CrtYd" user "Package Geometry/Place Bound Top")
		(29 "B.CrtYd" user "Package Geometry/Place Bound Bottom")
		(35 "F.Fab" user "Ref Des/Assembly Top")
		(33 "B.Fab" user "Ref Des/Assembly Bottom")
	)
	(footprint ""
		(layer "F.Cu")
		(at 145.128488 -395.436852 -90)
		(property "Reference" "R885"
			(at 0 0 270)
			(layer "F.SilkS")
			(hide yes)
			(effects
				(font
					(size 1.27 1.27)
				)
			)
		)
		(property "Value" ""
			(at 0 0 270)
			(layer "F.Fab")
			(effects
				(font
					(size 1.27 1.27)
				)
			)
		)
		(duplicate_pad_numbers_are_jumpers no)
		(fp_line
			(start -0.32512 0.175006)
			(end -0.32512 -0.175006)
			(stroke
				(width 0.1)
				(type default)
			)
			(layer "F.Fab")
		)
		(fp_line
			(start 0.32512 0.175006)
			(end -0.32512 0.175006)
			(stroke
				(width 0.1)
				(type default)
			)
			(layer "F.Fab")
		)
		(fp_line
			(start -0.32512 -0.175006)
			(end 0.32512 -0.175006)
			(stroke
				(width 0.1)
				(type default)
			)
			(layer "F.Fab")
		)
		(fp_line
			(start 0.32512 -0.175006)
			(end 0.32512 0.175006)
			(stroke
				(width 0.1)
				(type default)
			)
			(layer "F.Fab")
		)
		(pad "1" smd rect
			(at -0.2667 0 270)
			(size 0.3048 0.381)
			(layers "F.Cu" "F.Mask" "F.Paste")
			(net "P1V8_CPU1_RT_1D")
		)
		(pad "2" smd rect
			(at 0.2667 0 90)
			(size 0.3048 0.381)
			(layers "F.Cu" "F.Mask" "F.Paste")
			(net "MODE_RT_CPU1_P2")
		)
	)
	(footprint ""
		(layer "F.Cu")
		(at 12.360148 -387.30809 90)
		(property "Reference" "PR6624"
			(at 0 0 90)
			(layer "F.SilkS")
			(hide yes)
			(effects
				(font
					(size 1.27 1.27)
				)
			)
		)
		(property "Value" ""
			(at 0 0 90)
			(layer "F.Fab")
			(effects
				(font
					(size 1.27 1.27)
				)
			)
		)
		(duplicate_pad_numbers_are_jumpers no)
		(fp_line
			(start 0.7874 -0.4064)
			(end 0.7874 0.4064)
			(stroke
				(width 0.1524)
				(type default)
			)
			(layer "F.SilkS")
		)
		(fp_line
			(start -0.7874 -0.4064)
			(end 0.7874 -0.4064)
			(stroke
				(width 0.1524)
				(type default)
			)
			(layer "F.SilkS")
		)
		(fp_line
			(start 0.7874 0.4064)
			(end -0.7874 0.4064)
			(stroke
				(width 0.1524)
				(type default)
			)
			(layer "F.SilkS")
		)
		(fp_line
			(start -0.7874 0.4064)
			(end -0.7874 -0.4064)
			(stroke
				(width 0.1524)
				(type default)
			)
			(layer "F.SilkS")
		)
		(fp_line
			(start -0.12065 -0.305054)
			(end -0.12065 -0.2794)
			(stroke
				(width 0.1)
				(type default)
			)
			(layer "F.Fab")
		)
		(fp_line
			(start -0.67945 -0.305054)
			(end -0.12065 -0.305054)
			(stroke
				(width 0.1)
				(type default)
			)
			(layer "F.Fab")
		)
		(fp_line
			(start 0.67945 -0.3048)
			(end 0.67945 0.3048)
			(stroke
				(width 0.1)
				(type default)
			)
			(layer "F.Fab")
		)
		(fp_line
			(start 0.12065 -0.3048)
			(end 0.67945 -0.3048)
			(stroke
				(width 0.1)
				(type default)
			)
			(layer "F.Fab")
		)
		(fp_line
			(start 0.12065 -0.2794)
			(end 0.12065 -0.3048)
			(stroke
				(width 0.1)
				(type default)
			)
			(layer "F.Fab")
		)
		(fp_line
			(start -0.12065 -0.2794)
			(end 0.12065 -0.2794)
			(stroke
				(width 0.1)
				(type default)
			)
			(layer "F.Fab")
		)
		(fp_line
			(start 0.120396 0.2794)
			(end -0.12065 0.2794)
			(stroke
				(width 0.1)
				(type default)
			)
			(layer "F.Fab")
		)
		(fp_line
			(start -0.12065 0.2794)
			(end -0.12065 0.3048)
			(stroke
				(width 0.1)
				(type default)
			)
			(layer "F.Fab")
		)
		(fp_line
			(start 0.67945 0.3048)
			(end 0.120396 0.3048)
			(stroke
				(width 0.1)
				(type default)
			)
			(layer "F.Fab")
		)
		(fp_line
			(start 0.120396 0.3048)
			(end 0.120396 0.2794)
			(stroke
				(width 0.1)
				(type default)
			)
			(layer "F.Fab")
		)
		(fp_line
			(start -0.12065 0.3048)
			(end -0.67945 0.3048)
			(stroke
				(width 0.1)
				(type default)
			)
			(layer "F.Fab")
		)
		(fp_line
			(start -0.67945 0.3048)
			(end -0.67945 -0.305054)
			(stroke
				(width 0.1)
				(type default)
			)
			(layer "F.Fab")
		)
		(pad "1" smd circle
			(at -0.40005 0 90)
			(size 0 0)
			(layers "F.Cu" "F.Mask" "F.Paste")
			(net "SW_P0V9_RETIMER_CPU1_SW1_RC")
		)
		(pad "2" smd circle
			(at 0.40005 0 90)
			(size 0 0)
			(layers "F.Cu" "F.Mask" "F.Paste")
			(net "GND")
		)
	)
	(footprint ""
		(layer "F.Cu")
		(at 139.794742 -386.7912 90)
		(property "Reference" "R906"
			(at 0 0 90)
			(layer "F.SilkS")
			(hide yes)
			(effects
				(font
					(size 1.27 1.27)
				)
			)
		)
		(property "Value" ""
			(at 0 0 90)
			(layer "F.Fab")
			(effects
				(font
					(size 1.27 1.27)
				)
			)
		)
		(duplicate_pad_numbers_are_jumpers no)
		(fp_line
			(start 0.32512 -0.175006)
			(end 0.32512 0.175006)
			(stroke
				(width 0.1)
				(type default)
			)
			(layer "F.Fab")
		)
		(fp_line
			(start -0.32512 -0.175006)
			(end 0.32512 -0.175006)
			(stroke
				(width 0.1)
				(type default)
			)
			(layer "F.Fab")
		)
		(fp_line
			(start 0.32512 0.175006)
			(end -0.32512 0.175006)
			(stroke
				(width 0.1)
				(type default)
			)
			(layer "F.Fab")
		)
		(fp_line
			(start -0.32512 0.175006)
			(end -0.32512 -0.175006)
			(stroke
				(width 0.1)
				(type default)
			)
			(layer "F.Fab")
		)
		(pad "1" smd rect
			(at -0.2667 0 90)
			(size 0.3048 0.381)
			(layers "F.Cu" "F.Mask" "F.Paste")
			(net "RT_CPU1_P3_ADDR2")
		)
		(pad "2" smd rect
			(at 0.2667 0 270)
			(size 0.3048 0.381)
			(layers "F.Cu" "F.Mask" "F.Paste")
			(net "GND")
		)
	)
	(footprint ""
		(layer "F.Cu")
		(at 99.606862 -54.15153 90)
		(property "Reference" "C6088"
			(at 0 0 90)
			(layer "F.SilkS")
			(hide yes)
			(effects
				(font
					(size 1.27 1.27)
				)
			)
		)
		(property "Value" ""
			(at 0 0 90)
			(layer "F.Fab")
			(effects
				(font
					(size 1.27 1.27)
				)
			)
		)
		(duplicate_pad_numbers_are_jumpers no)
		(fp_line
			(start 1.524 -0.762)
			(end 1.524 0.762)
			(stroke
				(width 0.1524)
				(type default)
			)
			(layer "F.SilkS")
		)
		(fp_line
			(start -1.524 -0.762)
			(end 1.524 -0.762)
			(stroke
				(width 0.1524)
				(type default)
			)
			(layer "F.SilkS")
		)
		(fp_line
			(start 1.524 0.762)
			(end -1.524 0.762)
			(stroke
				(width 0.1524)
				(type default)
			)
			(layer "F.SilkS")
		)
		(fp_line
			(start -1.524 0.762)
			(end -1.524 -0.762)
			(stroke
				(width 0.1524)
				(type default)
			)
			(layer "F.SilkS")
		)
		(fp_line
			(start 1.1049 -0.724916)
			(end -1.1049 -0.724916)
			(stroke
				(width 0.1)
				(type default)
			)
			(layer "F.Fab")
		)
		(fp_line
			(start -1.1049 -0.724916)
			(end -1.1049 0.724916)
			(stroke
				(width 0.1)
				(type default)
			)
			(layer "F.Fab")
		)
		(fp_line
			(start 1.1049 0.724916)
			(end 1.1049 -0.724916)
			(stroke
				(width 0.1)
				(type default)
			)
			(layer "F.Fab")
		)
		(fp_line
			(start -1.1049 0.724916)
			(end 1.1049 0.724916)
			(stroke
				(width 0.1)
				(type default)
			)
			(layer "F.Fab")
		)
		(pad "1" smd rect
			(at -0.889 0 270)
			(size 1.016 1.27)
			(layers "F.Cu" "F.Mask" "F.Paste")
			(net "USB_HUB2_MRP_RESET_N")
		)
		(pad "2" smd rect
			(at 0.889 0 270)
			(size 1.016 1.27)
			(layers "F.Cu" "F.Mask" "F.Paste")
			(net "GND")
		)
	)
	(footprint ""
		(layer "F.Cu")
		(at 439.84164 -50.447448 180)
		(property "Reference" "PC566"
			(at 0.46228 -3.198368 0)
			(unlocked yes)
			(layer "F.SilkS")
			(effects
				(font
					(size 0.7874 0.5842)
					(thickness 0.1524)
				)
				(justify left)
			)
		)
		(property "Value" ""
			(at 0 0 180)
			(layer "F.Fab")
			(effects
				(font
					(size 1.27 1.27)
				)
			)
		)
		(duplicate_pad_numbers_are_jumpers no)
		(fp_line
			(start -3.400044 1.249934)
			(end 3.400044 1.249934)
			(stroke
				(width 0.1524)
				(type default)
			)
			(layer "F.SilkS")
		)
		(fp_circle
			(center 0 1.249934)
			(end -3.39979 1.249934)
			(stroke
				(width 0.1524)
				(type default)
			)
			(fill no)
			(layer "F.SilkS")
		)
		(fp_poly
			(pts
				(arc
					(start 3.400044 1.249934)
					(mid 0 4.649978)
					(end -3.400044 1.249934)
				)
			)
			(stroke
				(width 0)
				(type default)
			)
			(fill yes)
			(layer "F.SilkS")
		)
		(fp_circle
			(center 0 1.249934)
			(end -3.39979 1.249934)
			(stroke
				(width 0.1)
				(type default)
			)
			(fill no)
			(layer "F.Fab")
		)
		(pad "1" thru_hole rect
			(at 0 0 180)
			(size 1.524 1.524)
			(drill 1.016)
			(layers "*.Cu" "*.Mask")
			(remove_unused_layers no)
			(net "SW_P3V3_AUX_FLT")
			(clearance 0)
			(padstack
				(mode front_inner_back)
				(layer "Inner"
					(shape circle)
					(size 1.524 1.524)
					(clearance 0)
				)
				(layer "B.Cu"
					(shape rect)
					(size 1.524 1.524)
					(clearance 0)
				)
			)
		)
		(pad "2" thru_hole circle
			(at 0 2.500122 180)
			(size 1.524 1.524)
			(drill 1.016)
			(layers "*.Cu" "*.Mask")
			(remove_unused_layers no)
			(net "GND")
			(clearance 0)
		)
	)
	(footprint ""
		(layer "F.Cu")
		(at 365.835692 -257.455162 180)
		(property "Reference" "C2591"
			(at 0 0 180)
			(layer "F.SilkS")
			(hide yes)
			(effects
				(font
					(size 1.27 1.27)
				)
			)
		)
		(property "Value" ""
			(at 0 0 180)
			(layer "F.Fab")
			(effects
				(font
					(size 1.27 1.27)
				)
			)
		)
		(duplicate_pad_numbers_are_jumpers no)
		(fp_line
			(start 0.7874 0.4064)
			(end -0.7874 0.4064)
			(stroke
				(width 0.1524)
				(type default)
			)
			(layer "F.SilkS")
		)
		(fp_line
			(start 0.7874 -0.4064)
			(end 0.7874 0.4064)
			(stroke
				(width 0.1524)
				(type default)
			)
			(layer "F.SilkS")
		)
		(fp_line
			(start -0.7874 0.4064)
			(end -0.7874 -0.4064)
			(stroke
				(width 0.1524)
				(type default)
			)
			(layer "F.SilkS")
		)
		(fp_line
			(start -0.7874 -0.4064)
			(end 0.7874 -0.4064)
			(stroke
				(width 0.1524)
				(type default)
			)
			(layer "F.SilkS")
		)
		(fp_line
			(start 0.67945 0.3048)
			(end 0.120396 0.3048)
			(stroke
				(width 0.1)
				(type default)
			)
			(layer "F.Fab")
		)
		(fp_line
			(start 0.67945 -0.3048)
			(end 0.67945 0.3048)
			(stroke
				(width 0.1)
				(type default)
			)
			(layer "F.Fab")
		)
		(fp_line
			(start 0.12065 -0.2794)
			(end 0.12065 -0.3048)
			(stroke
				(width 0.1)
				(type default)
			)
			(layer "F.Fab")
		)
		(fp_line
			(start 0.12065 -0.3048)
			(end 0.67945 -0.3048)
			(stroke
				(width 0.1)
				(type default)
			)
			(layer "F.Fab")
		)
		(fp_line
			(start 0.120396 0.3048)
			(end 0.120396 0.2794)
			(stroke
				(width 0.1)
				(type default)
			)
			(layer "F.Fab")
		)
		(fp_line
			(start 0.120396 0.2794)
			(end -0.12065 0.2794)
			(stroke
				(width 0.1)
				(type default)
			)
			(layer "F.Fab")
		)
		(fp_line
			(start -0.12065 0.3048)
			(end -0.67945 0.3048)
			(stroke
				(width 0.1)
				(type default)
			)
			(layer "F.Fab")
		)
		(fp_line
			(start -0.12065 0.2794)
			(end -0.12065 0.3048)
			(stroke
				(width 0.1)
				(type default)
			)
			(layer "F.Fab")
		)
		(fp_line
			(start -0.12065 -0.2794)
			(end 0.12065 -0.2794)
			(stroke
				(width 0.1)
				(type default)
			)
			(layer "F.Fab")
		)
		(fp_line
			(start -0.12065 -0.305054)
			(end -0.12065 -0.2794)
			(stroke
				(width 0.1)
				(type default)
			)
			(layer "F.Fab")
		)
		(fp_line
			(start -0.67945 0.3048)
			(end -0.67945 -0.305054)
			(stroke
				(width 0.1)
				(type default)
			)
			(layer "F.Fab")
		)
		(fp_line
			(start -0.67945 -0.305054)
			(end -0.12065 -0.305054)
			(stroke
				(width 0.1)
				(type default)
			)
			(layer "F.Fab")
		)
		(pad "1" smd circle
			(at -0.40005 0 180)
			(size 0 0)
			(layers "F.Cu" "F.Mask" "F.Paste")
			(net "PVDDCR_SOC_P0")
		)
		(pad "2" smd circle
			(at 0.40005 0 180)
			(size 0 0)
			(layers "F.Cu" "F.Mask" "F.Paste")
			(net "GND")
		)
	)
	(footprint ""
		(layer "F.Cu")
		(at 380.39548 -33.228788 180)
		(property "Reference" "U320"
			(at 1.088136 2.603246 0)
			(unlocked yes)
			(layer "F.SilkS")
			(effects
				(font
					(size 0.7874 0.5842)
					(thickness 0.1524)
				)
				(justify left)
			)
		)
		(property "Value" ""
			(at 0 0 180)
			(layer "F.Fab")
			(effects
				(font
					(size 1.27 1.27)
				)
			)
		)
		(duplicate_pad_numbers_are_jumpers no)
		(fp_line
			(start 2.032 1.549908)
			(end -2.032 1.549908)
			(stroke
				(width 0.1524)
				(type default)
			)
			(layer "F.SilkS")
		)
		(fp_line
			(start 2.032 -1.549908)
			(end 2.032 1.549908)
			(stroke
				(width 0.1524)
				(type default)
			)
			(layer "F.SilkS")
		)
		(fp_line
			(start -2.032 1.549908)
			(end -2.032 -1.549908)
			(stroke
				(width 0.1524)
				(type default)
			)
			(layer "F.SilkS")
		)
		(fp_line
			(start -2.032 -1.549908)
			(end 2.032 -1.549908)
			(stroke
				(width 0.1524)
				(type default)
			)
			(layer "F.SilkS")
		)
		(fp_poly
			(pts
				(xy -2.9464 -1.2192) (xy -2.9464 -0.7112) (xy -2.1844 -0.9652)
			)
			(stroke
				(width 0)
				(type default)
			)
			(fill yes)
			(layer "F.SilkS")
		)
		(fp_line
			(start 0.849884 1.549908)
			(end 0.849884 -1.549908)
			(stroke
				(width 0.1)
				(type default)
			)
			(layer "F.Fab")
		)
		(fp_line
			(start 0.849884 -1.549908)
			(end -0.849884 -1.549908)
			(stroke
				(width 0.1)
				(type default)
			)
			(layer "F.Fab")
		)
		(fp_line
			(start -0.849884 1.549908)
			(end 0.849884 1.549908)
			(stroke
				(width 0.1)
				(type default)
			)
			(layer "F.Fab")
		)
		(fp_line
			(start -0.849884 -1.549908)
			(end -0.849884 1.549908)
			(stroke
				(width 0.1)
				(type default)
			)
			(layer "F.Fab")
		)
		(fp_poly
			(pts
				(xy -2.9464 -1.2192) (xy -2.9464 -0.7112) (xy -2.1844 -0.9652)
			)
			(stroke
				(width 0)
				(type default)
			)
			(fill yes)
			(layer "F.Fab")
		)
		(pad "1" smd rect
			(at -1.225042 -0.94996 90)
			(size 0.4572 1.3208)
			(layers "F.Cu" "F.Mask" "F.Paste")
			(net "CLK_50M_NCSI_OCP_SFF")
		)
		(pad "2" smd rect
			(at -1.225042 0 90)
			(size 0.4572 1.3208)
			(layers "F.Cu" "F.Mask" "F.Paste")
			(net "CLK_50M_NCSI_OCP_SFF_ISO_R")
		)
		(pad "3" smd rect
			(at -1.225042 0.94996 90)
			(size 0.4572 1.3208)
			(layers "F.Cu" "F.Mask" "F.Paste")
			(net "GND")
		)
		(pad "4" smd rect
			(at 1.225042 0.94996 90)
			(size 0.4572 1.3208)
			(layers "F.Cu" "F.Mask" "F.Paste")
			(net "FB_BMC_ISOLATE")
		)
		(pad "5" smd rect
			(at 1.225042 -0.94996 90)
			(size 0.4572 1.3208)
			(layers "F.Cu" "F.Mask" "F.Paste")
			(net "P3V3_AUX")
		)
	)
	(footprint ""
		(layer "F.Cu")
		(at 18.483072 -393.394184 -90)
		(property "Reference" "PC6621"
			(at 0 0 270)
			(layer "F.SilkS")
			(hide yes)
			(effects
				(font
					(size 1.27 1.27)
				)
			)
		)
		(property "Value" ""
			(at 0 0 270)
			(layer "F.Fab")
			(effects
				(font
					(size 1.27 1.27)
				)
			)
		)
		(duplicate_pad_numbers_are_jumpers no)
		(fp_line
			(start -0.7874 0.4064)
			(end -0.7874 -0.4064)
			(stroke
				(width 0.1524)
				(type default)
			)
			(layer "F.SilkS")
		)
		(fp_line
			(start 0.7874 0.4064)
			(end -0.7874 0.4064)
			(stroke
				(width 0.1524)
				(type default)
			)
			(layer "F.SilkS")
		)
		(fp_line
			(start -0.7874 -0.4064)
			(end 0.7874 -0.4064)
			(stroke
				(width 0.1524)
				(type default)
			)
			(layer "F.SilkS")
		)
		(fp_line
			(start 0.7874 -0.4064)
			(end 0.7874 0.4064)
			(stroke
				(width 0.1524)
				(type default)
			)
			(layer "F.SilkS")
		)
		(fp_line
			(start -0.67945 0.3048)
			(end -0.67945 -0.305054)
			(stroke
				(width 0.1)
				(type default)
			)
			(layer "F.Fab")
		)
		(fp_line
			(start -0.12065 0.3048)
			(end -0.67945 0.3048)
			(stroke
				(width 0.1)
				(type default)
			)
			(layer "F.Fab")
		)
		(fp_line
			(start 0.120396 0.3048)
			(end 0.120396 0.2794)
			(stroke
				(width 0.1)
				(type default)
			)
			(layer "F.Fab")
		)
		(fp_line
			(start 0.67945 0.3048)
			(end 0.120396 0.3048)
			(stroke
				(width 0.1)
				(type default)
			)
			(layer "F.Fab")
		)
		(fp_line
			(start -0.12065 0.2794)
			(end -0.12065 0.3048)
			(stroke
				(width 0.1)
				(type default)
			)
			(layer "F.Fab")
		)
		(fp_line
			(start 0.120396 0.2794)
			(end -0.12065 0.2794)
			(stroke
				(width 0.1)
				(type default)
			)
			(layer "F.Fab")
		)
		(fp_line
			(start -0.12065 -0.2794)
			(end 0.12065 -0.2794)
			(stroke
				(width 0.1)
				(type default)
			)
			(layer "F.Fab")
		)
		(fp_line
			(start 0.12065 -0.2794)
			(end 0.12065 -0.3048)
			(stroke
				(width 0.1)
				(type default)
			)
			(layer "F.Fab")
		)
		(fp_line
			(start 0.12065 -0.3048)
			(end 0.67945 -0.3048)
			(stroke
				(width 0.1)
				(type default)
			)
			(layer "F.Fab")
		)
		(fp_line
			(start 0.67945 -0.3048)
			(end 0.67945 0.3048)
			(stroke
				(width 0.1)
				(type default)
			)
			(layer "F.Fab")
		)
		(fp_line
			(start -0.67945 -0.305054)
			(end -0.12065 -0.305054)
			(stroke
				(width 0.1)
				(type default)
			)
			(layer "F.Fab")
		)
		(fp_line
			(start -0.12065 -0.305054)
			(end -0.12065 -0.2794)
			(stroke
				(width 0.1)
				(type default)
			)
			(layer "F.Fab")
		)
		(pad "1" smd circle
			(at -0.40005 0 270)
			(size 0 0)
			(layers "F.Cu" "F.Mask" "F.Paste")
			(net "SW_P0V9_RETIMER_CPU1_BOOT1_RC")
		)
		(pad "2" smd circle
			(at 0.40005 0 270)
			(size 0 0)
			(layers "F.Cu" "F.Mask" "F.Paste")
			(net "SW_P0V9_RETIMER_CPU1_PH1")
		)
	)
	(footprint ""
		(layer "F.Cu")
		(at 294.581072 -394.721842 180)
		(property "Reference" "R1415"
			(at 0 0 180)
			(layer "F.SilkS")
			(hide yes)
			(effects
				(font
					(size 1.27 1.27)
				)
			)
		)
		(property "Value" ""
			(at 0 0 180)
			(layer "F.Fab")
			(effects
				(font
					(size 1.27 1.27)
				)
			)
		)
		(duplicate_pad_numbers_are_jumpers no)
		(fp_line
			(start 0.32512 0.175006)
			(end -0.32512 0.175006)
			(stroke
				(width 0.1)
				(type default)
			)
			(layer "F.Fab")
		)
		(fp_line
			(start 0.32512 -0.175006)
			(end 0.32512 0.175006)
			(stroke
				(width 0.1)
				(type default)
			)
			(layer "F.Fab")
		)
		(fp_line
			(start -0.32512 0.175006)
			(end -0.32512 -0.175006)
			(stroke
				(width 0.1)
				(type default)
			)
			(layer "F.Fab")
		)
		(fp_line
			(start -0.32512 -0.175006)
			(end 0.32512 -0.175006)
			(stroke
				(width 0.1)
				(type default)
			)
			(layer "F.Fab")
		)
		(pad "1" smd rect
			(at -0.2667 0 180)
			(size 0.3048 0.381)
			(layers "F.Cu" "F.Mask" "F.Paste")
			(net "P1V8_CPU0_RT_1D")
		)
		(pad "2" smd rect
			(at 0.2667 0)
			(size 0.3048 0.381)
			(layers "F.Cu" "F.Mask" "F.Paste")
			(net "SMB_RT_CPU0_P1_ROM_MUX_1D_SDA")
		)
	)
)
